(kicad_pcb
	(version 20260206)
	(generator "pcbnew")
	(generator_version "10.0")
	(general
		(thickness 1.6)
		(legacy_teardrops no)
	)
	(paper "A4")
	(title_block
		(title "03242023_DA0F0TMBIJ0_F0T_Motherboard_J_brd_V01_OCP.brd")
		(comment 1 "Grand Teton / footprints 6045-6050 of 6105")
	)
	(layers
		(0 "F.Cu" signal "TOP")
		(4 "In1.Cu" signal "GND")
		(6 "In2.Cu" signal "IN1")
		(8 "In3.Cu" signal "GND1")
		(10 "In4.Cu" signal "IN2")
		(12 "In5.Cu" signal "GND2")
		(14 "In6.Cu" signal "IN3")
		(16 "In7.Cu" signal "GND3")
		(18 "In8.Cu" signal "VCC")
		(20 "In9.Cu" signal "VCC1")
		(22 "In10.Cu" signal "GND4")
		(24 "In11.Cu" signal "IN4")
		(26 "In12.Cu" signal "GND5")
		(28 "In13.Cu" signal "IN5")
		(30 "In14.Cu" signal "GND6")
		(32 "In15.Cu" signal "IN6")
		(34 "In16.Cu" signal "GND7")
		(2 "B.Cu" signal "BOTTOM")
		(9 "F.Adhes" user "F.Adhesive")
		(11 "B.Adhes" user "B.Adhesive")
		(13 "F.Paste" user "Package Geometry/Pastemask Top")
		(15 "B.Paste" user "Package Geometry/Pastemask Bottom")
		(5 "F.SilkS" user "Ref Des/Silkscreen Top")
		(7 "B.SilkS" user "Ref Des/Silkscreen Bottom")
		(1 "F.Mask" user "Board Geometry/Soldermask Top")
		(3 "B.Mask" user "Board Geometry/Soldermask Bottom")
		(17 "Dwgs.User" user "User.Drawings")
		(19 "Cmts.User" user "User.Comments")
		(21 "Eco1.User" user "User.Eco1")
		(23 "Eco2.User" user "User.Eco2")
		(25 "Edge.Cuts" user "Board Geometry/Outline")
		(27 "Margin" user)
		(31 "F.CrtYd" user "Package Geometry/Place Bound Top")
		(29 "B.CrtYd" user "Package Geometry/Place Bound Bottom")
		(35 "F.Fab" user "Ref Des/Assembly Top")
		(33 "B.Fab" user "Ref Des/Assembly Bottom")
	)
	(footprint ""
		(layer "B.Cu")
		(at 245.835424 -100.121212)
		(property "Reference" "R734"
			(at 0 0 0)
			(layer "B.SilkS")
			(hide yes)
			(effects
				(font
					(size 1.27 1.27)
				)
				(justify mirror)
			)
		)
		(property "Value" ""
			(at 0 0 0)
			(layer "B.Fab")
			(effects
				(font
					(size 1.27 1.27)
				)
				(justify mirror)
			)
		)
		(duplicate_pad_numbers_are_jumpers no)
		(fp_line
			(start -0.7874 -0.4064)
			(end -0.7874 0.4064)
			(stroke
				(width 0.1524)
				(type default)
			)
			(layer "B.SilkS")
		)
		(fp_line
			(start -0.7874 0.4064)
			(end 0.7874 0.4064)
			(stroke
				(width 0.1524)
				(type default)
			)
			(layer "B.SilkS")
		)
		(fp_line
			(start 0.7874 -0.4064)
			(end -0.7874 -0.4064)
			(stroke
				(width 0.1524)
				(type default)
			)
			(layer "B.SilkS")
		)
		(fp_line
			(start 0.7874 0.4064)
			(end 0.7874 -0.4064)
			(stroke
				(width 0.1524)
				(type default)
			)
			(layer "B.SilkS")
		)
		(fp_line
			(start -0.67945 -0.3048)
			(end -0.67945 0.3048)
			(stroke
				(width 0.1)
				(type default)
			)
			(layer "B.Fab")
		)
		(fp_line
			(start -0.67945 0.3048)
			(end -0.120396 0.3048)
			(stroke
				(width 0.1)
				(type default)
			)
			(layer "B.Fab")
		)
		(fp_line
			(start -0.12065 -0.3048)
			(end -0.67945 -0.3048)
			(stroke
				(width 0.1)
				(type default)
			)
			(layer "B.Fab")
		)
		(fp_line
			(start -0.12065 -0.2794)
			(end -0.12065 -0.3048)
			(stroke
				(width 0.1)
				(type default)
			)
			(layer "B.Fab")
		)
		(fp_line
			(start -0.120396 0.2794)
			(end 0.12065 0.2794)
			(stroke
				(width 0.1)
				(type default)
			)
			(layer "B.Fab")
		)
		(fp_line
			(start -0.120396 0.3048)
			(end -0.120396 0.2794)
			(stroke
				(width 0.1)
				(type default)
			)
			(layer "B.Fab")
		)
		(fp_line
			(start 0.12065 -0.305054)
			(end 0.12065 -0.2794)
			(stroke
				(width 0.1)
				(type default)
			)
			(layer "B.Fab")
		)
		(fp_line
			(start 0.12065 -0.2794)
			(end -0.12065 -0.2794)
			(stroke
				(width 0.1)
				(type default)
			)
			(layer "B.Fab")
		)
		(fp_line
			(start 0.12065 0.2794)
			(end 0.12065 0.3048)
			(stroke
				(width 0.1)
				(type default)
			)
			(layer "B.Fab")
		)
		(fp_line
			(start 0.12065 0.3048)
			(end 0.67945 0.3048)
			(stroke
				(width 0.1)
				(type default)
			)
			(layer "B.Fab")
		)
		(fp_line
			(start 0.67945 -0.305054)
			(end 0.12065 -0.305054)
			(stroke
				(width 0.1)
				(type default)
			)
			(layer "B.Fab")
		)
		(fp_line
			(start 0.67945 0.3048)
			(end 0.67945 -0.305054)
			(stroke
				(width 0.1)
				(type default)
			)
			(layer "B.Fab")
		)
		(pad "1" smd circle
			(at 0.40005 0 180)
			(size 0 0)
			(layers "B.Cu" "B.Mask" "B.Paste")
			(net "CLK_CK440_SMB_ADDR1")
		)
		(pad "2" smd circle
			(at -0.40005 0 180)
			(size 0 0)
			(layers "B.Cu" "B.Mask" "B.Paste")
			(net "GND")
		)
	)
	(footprint ""
		(layer "B.Cu")
		(at 160.30702 -14.549628 -90)
		(property "Reference" "R592"
			(at 0 0 90)
			(layer "B.SilkS")
			(hide yes)
			(effects
				(font
					(size 1.27 1.27)
				)
				(justify mirror)
			)
		)
		(property "Value" ""
			(at 0 0 90)
			(layer "B.Fab")
			(effects
				(font
					(size 1.27 1.27)
				)
				(justify mirror)
			)
		)
		(duplicate_pad_numbers_are_jumpers no)
		(fp_line
			(start -0.7874 0.4064)
			(end 0.7874 0.4064)
			(stroke
				(width 0.1524)
				(type default)
			)
			(layer "B.SilkS")
		)
		(fp_line
			(start 0.7874 0.4064)
			(end 0.7874 -0.4064)
			(stroke
				(width 0.1524)
				(type default)
			)
			(layer "B.SilkS")
		)
		(fp_line
			(start -0.7874 -0.4064)
			(end -0.7874 0.4064)
			(stroke
				(width 0.1524)
				(type default)
			)
			(layer "B.SilkS")
		)
		(fp_line
			(start 0.7874 -0.4064)
			(end -0.7874 -0.4064)
			(stroke
				(width 0.1524)
				(type default)
			)
			(layer "B.SilkS")
		)
		(fp_line
			(start -0.67945 0.3048)
			(end -0.120396 0.3048)
			(stroke
				(width 0.1)
				(type default)
			)
			(layer "B.Fab")
		)
		(fp_line
			(start -0.120396 0.3048)
			(end -0.120396 0.2794)
			(stroke
				(width 0.1)
				(type default)
			)
			(layer "B.Fab")
		)
		(fp_line
			(start 0.12065 0.3048)
			(end 0.67945 0.3048)
			(stroke
				(width 0.1)
				(type default)
			)
			(layer "B.Fab")
		)
		(fp_line
			(start 0.67945 0.3048)
			(end 0.67945 -0.305054)
			(stroke
				(width 0.1)
				(type default)
			)
			(layer "B.Fab")
		)
		(fp_line
			(start -0.120396 0.2794)
			(end 0.12065 0.2794)
			(stroke
				(width 0.1)
				(type default)
			)
			(layer "B.Fab")
		)
		(fp_line
			(start 0.12065 0.2794)
			(end 0.12065 0.3048)
			(stroke
				(width 0.1)
				(type default)
			)
			(layer "B.Fab")
		)
		(fp_line
			(start -0.12065 -0.2794)
			(end -0.12065 -0.3048)
			(stroke
				(width 0.1)
				(type default)
			)
			(layer "B.Fab")
		)
		(fp_line
			(start 0.12065 -0.2794)
			(end -0.12065 -0.2794)
			(stroke
				(width 0.1)
				(type default)
			)
			(layer "B.Fab")
		)
		(fp_line
			(start -0.67945 -0.3048)
			(end -0.67945 0.3048)
			(stroke
				(width 0.1)
				(type default)
			)
			(layer "B.Fab")
		)
		(fp_line
			(start -0.12065 -0.3048)
			(end -0.67945 -0.3048)
			(stroke
				(width 0.1)
				(type default)
			)
			(layer "B.Fab")
		)
		(fp_line
			(start 0.12065 -0.305054)
			(end 0.12065 -0.2794)
			(stroke
				(width 0.1)
				(type default)
			)
			(layer "B.Fab")
		)
		(fp_line
			(start 0.67945 -0.305054)
			(end 0.12065 -0.305054)
			(stroke
				(width 0.1)
				(type default)
			)
			(layer "B.Fab")
		)
		(pad "1" smd circle
			(at 0.40005 0 90)
			(size 0 0)
			(layers "B.Cu" "B.Mask" "B.Paste")
			(net "SMB_FAN_3V3AUX_SCL")
		)
		(pad "2" smd circle
			(at -0.40005 0 90)
			(size 0 0)
			(layers "B.Cu" "B.Mask" "B.Paste")
			(net "P3V3_AUX")
		)
	)
	(footprint ""
		(layer "B.Cu")
		(at 164.64788 -113.756948 180)
		(property "Reference" "R3486"
			(at 0 0 0)
			(layer "B.SilkS")
			(hide yes)
			(effects
				(font
					(size 1.27 1.27)
				)
				(justify mirror)
			)
		)
		(property "Value" ""
			(at 0 0 0)
			(layer "B.Fab")
			(effects
				(font
					(size 1.27 1.27)
				)
				(justify mirror)
			)
		)
		(duplicate_pad_numbers_are_jumpers no)
		(fp_line
			(start 0.7874 0.4064)
			(end 0.7874 -0.4064)
			(stroke
				(width 0.1524)
				(type default)
			)
			(layer "B.SilkS")
		)
		(fp_line
			(start 0.7874 -0.4064)
			(end -0.7874 -0.4064)
			(stroke
				(width 0.1524)
				(type default)
			)
			(layer "B.SilkS")
		)
		(fp_line
			(start -0.7874 0.4064)
			(end 0.7874 0.4064)
			(stroke
				(width 0.1524)
				(type default)
			)
			(layer "B.SilkS")
		)
		(fp_line
			(start -0.7874 -0.4064)
			(end -0.7874 0.4064)
			(stroke
				(width 0.1524)
				(type default)
			)
			(layer "B.SilkS")
		)
		(fp_line
			(start 0.67945 0.3048)
			(end 0.67945 -0.305054)
			(stroke
				(width 0.1)
				(type default)
			)
			(layer "B.Fab")
		)
		(fp_line
			(start 0.67945 -0.305054)
			(end 0.12065 -0.305054)
			(stroke
				(width 0.1)
				(type default)
			)
			(layer "B.Fab")
		)
		(fp_line
			(start 0.12065 0.3048)
			(end 0.67945 0.3048)
			(stroke
				(width 0.1)
				(type default)
			)
			(layer "B.Fab")
		)
		(fp_line
			(start 0.12065 0.2794)
			(end 0.12065 0.3048)
			(stroke
				(width 0.1)
				(type default)
			)
			(layer "B.Fab")
		)
		(fp_line
			(start 0.12065 -0.2794)
			(end -0.12065 -0.2794)
			(stroke
				(width 0.1)
				(type default)
			)
			(layer "B.Fab")
		)
		(fp_line
			(start 0.12065 -0.305054)
			(end 0.12065 -0.2794)
			(stroke
				(width 0.1)
				(type default)
			)
			(layer "B.Fab")
		)
		(fp_line
			(start -0.120396 0.3048)
			(end -0.120396 0.2794)
			(stroke
				(width 0.1)
				(type default)
			)
			(layer "B.Fab")
		)
		(fp_line
			(start -0.120396 0.2794)
			(end 0.12065 0.2794)
			(stroke
				(width 0.1)
				(type default)
			)
			(layer "B.Fab")
		)
		(fp_line
			(start -0.12065 -0.2794)
			(end -0.12065 -0.3048)
			(stroke
				(width 0.1)
				(type default)
			)
			(layer "B.Fab")
		)
		(fp_line
			(start -0.12065 -0.3048)
			(end -0.67945 -0.3048)
			(stroke
				(width 0.1)
				(type default)
			)
			(layer "B.Fab")
		)
		(fp_line
			(start -0.67945 0.3048)
			(end -0.120396 0.3048)
			(stroke
				(width 0.1)
				(type default)
			)
			(layer "B.Fab")
		)
		(fp_line
			(start -0.67945 -0.3048)
			(end -0.67945 0.3048)
			(stroke
				(width 0.1)
				(type default)
			)
			(layer "B.Fab")
		)
		(pad "1" smd circle
			(at 0.40005 0)
			(size 0 0)
			(layers "B.Cu" "B.Mask" "B.Paste")
			(net "GPU_PRSNT_N_ISO")
		)
		(pad "2" smd circle
			(at -0.40005 0)
			(size 0 0)
			(layers "B.Cu" "B.Mask" "B.Paste")
			(net "GPU_PRSNT_N_ISO_R")
		)
	)
	(footprint ""
		(layer "B.Cu")
		(at 367.778538 -189.56147)
		(property "Reference" "C561"
			(at 0 0 0)
			(layer "B.SilkS")
			(hide yes)
			(effects
				(font
					(size 1.27 1.27)
				)
				(justify mirror)
			)
		)
		(property "Value" ""
			(at 0 0 0)
			(layer "B.Fab")
			(effects
				(font
					(size 1.27 1.27)
				)
				(justify mirror)
			)
		)
		(duplicate_pad_numbers_are_jumpers no)
		(fp_line
			(start -0.7874 -0.4064)
			(end -0.7874 0.4064)
			(stroke
				(width 0.1524)
				(type default)
			)
			(layer "B.SilkS")
		)
		(fp_line
			(start -0.7874 0.4064)
			(end 0.7874 0.4064)
			(stroke
				(width 0.1524)
				(type default)
			)
			(layer "B.SilkS")
		)
		(fp_line
			(start 0.7874 -0.4064)
			(end -0.7874 -0.4064)
			(stroke
				(width 0.1524)
				(type default)
			)
			(layer "B.SilkS")
		)
		(fp_line
			(start 0.7874 0.4064)
			(end 0.7874 -0.4064)
			(stroke
				(width 0.1524)
				(type default)
			)
			(layer "B.SilkS")
		)
		(fp_line
			(start -0.67945 -0.3048)
			(end -0.67945 0.3048)
			(stroke
				(width 0.1)
				(type default)
			)
			(layer "B.Fab")
		)
		(fp_line
			(start -0.67945 0.3048)
			(end -0.120396 0.3048)
			(stroke
				(width 0.1)
				(type default)
			)
			(layer "B.Fab")
		)
		(fp_line
			(start -0.12065 -0.3048)
			(end -0.67945 -0.3048)
			(stroke
				(width 0.1)
				(type default)
			)
			(layer "B.Fab")
		)
		(fp_line
			(start -0.12065 -0.2794)
			(end -0.12065 -0.3048)
			(stroke
				(width 0.1)
				(type default)
			)
			(layer "B.Fab")
		)
		(fp_line
			(start -0.120396 0.2794)
			(end 0.12065 0.2794)
			(stroke
				(width 0.1)
				(type default)
			)
			(layer "B.Fab")
		)
		(fp_line
			(start -0.120396 0.3048)
			(end -0.120396 0.2794)
			(stroke
				(width 0.1)
				(type default)
			)
			(layer "B.Fab")
		)
		(fp_line
			(start 0.12065 -0.305054)
			(end 0.12065 -0.2794)
			(stroke
				(width 0.1)
				(type default)
			)
			(layer "B.Fab")
		)
		(fp_line
			(start 0.12065 -0.2794)
			(end -0.12065 -0.2794)
			(stroke
				(width 0.1)
				(type default)
			)
			(layer "B.Fab")
		)
		(fp_line
			(start 0.12065 0.2794)
			(end 0.12065 0.3048)
			(stroke
				(width 0.1)
				(type default)
			)
			(layer "B.Fab")
		)
		(fp_line
			(start 0.12065 0.3048)
			(end 0.67945 0.3048)
			(stroke
				(width 0.1)
				(type default)
			)
			(layer "B.Fab")
		)
		(fp_line
			(start 0.67945 -0.305054)
			(end 0.12065 -0.305054)
			(stroke
				(width 0.1)
				(type default)
			)
			(layer "B.Fab")
		)
		(fp_line
			(start 0.67945 0.3048)
			(end 0.67945 -0.305054)
			(stroke
				(width 0.1)
				(type default)
			)
			(layer "B.Fab")
		)
		(pad "1" smd circle
			(at 0.40005 0 180)
			(size 0 0)
			(layers "B.Cu" "B.Mask" "B.Paste")
			(net "P3V3_AUX")
		)
		(pad "2" smd circle
			(at -0.40005 0 180)
			(size 0 0)
			(layers "B.Cu" "B.Mask" "B.Paste")
			(net "GND")
		)
	)
	(footprint ""
		(layer "B.Cu")
		(at 163.851082 -8.916924 90)
		(property "Reference" "R589"
			(at 0 0 90)
			(layer "B.SilkS")
			(hide yes)
			(effects
				(font
					(size 1.27 1.27)
				)
				(justify mirror)
			)
		)
		(property "Value" ""
			(at 0 0 90)
			(layer "B.Fab")
			(effects
				(font
					(size 1.27 1.27)
				)
				(justify mirror)
			)
		)
		(duplicate_pad_numbers_are_jumpers no)
		(fp_line
			(start 0.7874 -0.4064)
			(end -0.7874 -0.4064)
			(stroke
				(width 0.1524)
				(type default)
			)
			(layer "B.SilkS")
		)
		(fp_line
			(start -0.7874 -0.4064)
			(end -0.7874 0.4064)
			(stroke
				(width 0.1524)
				(type default)
			)
			(layer "B.SilkS")
		)
		(fp_line
			(start 0.7874 0.4064)
			(end 0.7874 -0.4064)
			(stroke
				(width 0.1524)
				(type default)
			)
			(layer "B.SilkS")
		)
		(fp_line
			(start -0.7874 0.4064)
			(end 0.7874 0.4064)
			(stroke
				(width 0.1524)
				(type default)
			)
			(layer "B.SilkS")
		)
		(fp_line
			(start 0.67945 -0.305054)
			(end 0.12065 -0.305054)
			(stroke
				(width 0.1)
				(type default)
			)
			(layer "B.Fab")
		)
		(fp_line
			(start 0.12065 -0.305054)
			(end 0.12065 -0.2794)
			(stroke
				(width 0.1)
				(type default)
			)
			(layer "B.Fab")
		)
		(fp_line
			(start -0.12065 -0.3048)
			(end -0.67945 -0.3048)
			(stroke
				(width 0.1)
				(type default)
			)
			(layer "B.Fab")
		)
		(fp_line
			(start -0.67945 -0.3048)
			(end -0.67945 0.3048)
			(stroke
				(width 0.1)
				(type default)
			)
			(layer "B.Fab")
		)
		(fp_line
			(start 0.12065 -0.2794)
			(end -0.12065 -0.2794)
			(stroke
				(width 0.1)
				(type default)
			)
			(layer "B.Fab")
		)
		(fp_line
			(start -0.12065 -0.2794)
			(end -0.12065 -0.3048)
			(stroke
				(width 0.1)
				(type default)
			)
			(layer "B.Fab")
		)
		(fp_line
			(start 0.12065 0.2794)
			(end 0.12065 0.3048)
			(stroke
				(width 0.1)
				(type default)
			)
			(layer "B.Fab")
		)
		(fp_line
			(start -0.120396 0.2794)
			(end 0.12065 0.2794)
			(stroke
				(width 0.1)
				(type default)
			)
			(layer "B.Fab")
		)
		(fp_line
			(start 0.67945 0.3048)
			(end 0.67945 -0.305054)
			(stroke
				(width 0.1)
				(type default)
			)
			(layer "B.Fab")
		)
		(fp_line
			(start 0.12065 0.3048)
			(end 0.67945 0.3048)
			(stroke
				(width 0.1)
				(type default)
			)
			(layer "B.Fab")
		)
		(fp_line
			(start -0.120396 0.3048)
			(end -0.120396 0.2794)
			(stroke
				(width 0.1)
				(type default)
			)
			(layer "B.Fab")
		)
		(fp_line
			(start -0.67945 0.3048)
			(end -0.120396 0.3048)
			(stroke
				(width 0.1)
				(type default)
			)
			(layer "B.Fab")
		)
		(pad "1" smd circle
			(at 0.40005 0 270)
			(size 0 0)
			(layers "B.Cu" "B.Mask" "B.Paste")
			(net "SMB_PCIE0_3V3AUX_SDA")
		)
		(pad "2" smd circle
			(at -0.40005 0 270)
			(size 0 0)
			(layers "B.Cu" "B.Mask" "B.Paste")
			(net "SMB_PCIE0_3V3AUX_SDA_R")
		)
	)
	(footprint ""
		(layer "B.Cu")
		(at 292.04285 -362.795058 90)
		(property "Reference" "PC1182_P0_4"
			(at 0 0 90)
			(layer "B.SilkS")
			(hide yes)
			(effects
				(font
					(size 1.27 1.27)
				)
				(justify mirror)
			)
		)
		(property "Value" ""
			(at 0 0 90)
			(layer "B.Fab")
			(effects
				(font
					(size 1.27 1.27)
				)
				(justify mirror)
			)
		)
		(duplicate_pad_numbers_are_jumpers no)
		(fp_line
			(start 1.524 -0.762)
			(end -1.524 -0.762)
			(stroke
				(width 0.1524)
				(type default)
			)
			(layer "B.SilkS")
		)
		(fp_line
			(start -1.524 -0.762)
			(end -1.524 0.762)
			(stroke
				(width 0.1524)
				(type default)
			)
			(layer "B.SilkS")
		)
		(fp_line
			(start 1.524 0.762)
			(end 1.524 -0.762)
			(stroke
				(width 0.1524)
				(type default)
			)
			(layer "B.SilkS")
		)
		(fp_line
			(start -1.524 0.762)
			(end 1.524 0.762)
			(stroke
				(width 0.1524)
				(type default)
			)
			(layer "B.SilkS")
		)
		(fp_line
			(start 1.1049 -0.724916)
			(end 1.1049 0.724916)
			(stroke
				(width 0.1)
				(type default)
			)
			(layer "B.Fab")
		)
		(fp_line
			(start -1.1049 -0.724916)
			(end 1.1049 -0.724916)
			(stroke
				(width 0.1)
				(type default)
			)
			(layer "B.Fab")
		)
		(fp_line
			(start 1.1049 0.724916)
			(end -1.1049 0.724916)
			(stroke
				(width 0.1)
				(type default)
			)
			(layer "B.Fab")
		)
		(fp_line
			(start -1.1049 0.724916)
			(end -1.1049 -0.724916)
			(stroke
				(width 0.1)
				(type default)
			)
			(layer "B.Fab")
		)
		(pad "1" smd rect
			(at 0.889 0 90)
			(size 1.016 1.27)
			(layers "B.Cu" "B.Mask" "B.Paste")
			(net "SW_P12V_PVCCFA_EHV_FIVRA_CPU0_L")
		)
		(pad "2" smd rect
			(at -0.889 0 90)
			(size 1.016 1.27)
			(layers "B.Cu" "B.Mask" "B.Paste")
			(net "GND")
		)
	)
)
